G04 ================== begin FILE IDENTIFICATION RECORD ==================*
G04 Layout Name:  16368-sb.brd*
G04 Film Name:    P_OUTLINE*
G04 File Format:  Gerber RS274X*
G04 File Origin:  Cadence Allegro 16.5-S056*
G04 Origin Date:  Tue Feb 07 09:07:38 2017*
G04 *
G04 Layer:  BOARD GEOMETRY/PANEL_OUTLINE*
G04 *
G04 Offset:    (0.00 0.00)*
G04 Mirror:    No*
G04 Mode:      Positive*
G04 Rotation:  0*
G04 FullContactRelief:  No*
G04 UndefLineWidth:     6.00*
G04 ================== end FILE IDENTIFICATION RECORD ====================*
%FSLAX35Y35*MOIN*%
%IR0*IPPOS*OFA0.00000B0.00000*MIA0B0*SFA1.00000B1.00000*%
%ADD10C,.006*%
G75*
%LPD*%
G75*
G54D10*
G01X0Y-11811D02*
G03X7874Y-19685I7874J0D01*
G01X37008Y0D02*
G03Y-7874I0J-3937D01*
G01X11811D02*
G03Y0I0J3937D01*
G01X0Y-7874D02*
Y-11811D01*
G01X7874Y-19685D02*
X181690D01*
G01X0Y-7874D02*
X11811D01*
G01X25985Y19685D02*
G03X9449I-8268J0D01*
G01D02*
G03X25985I8268J0D01*
G01D02*
G03X9449I-8268J0D01*
G01D02*
G03X25985I8268J0D01*
G01D02*
G03X9449I-8268J0D01*
G01D02*
G03X25985I8268J0D01*
G01D02*
G03X9449I-8268J0D01*
G01D02*
G03X25985I8268J0D01*
G01X9449D02*
G03X25985I8268J0D01*
G01D02*
G03X9449I-8268J0D01*
G01D02*
G03X25985I8268J0D01*
G01D02*
G03X9449I-8268J0D01*
G01X3937Y0D02*
X173229D01*
G01X0Y3937D02*
G03X3937Y0I3937J0D01*
G01X0Y57874D02*
Y3937D01*
G01X37008Y69685D02*
G03Y61811I0J-3937D01*
G01X11811D02*
G03Y69685I0J3937D01*
G01X25985Y89370D02*
G03X9449I-8268J0D01*
G01D02*
G03X25985I8268J0D01*
G01D02*
G03X9449I-8268J0D01*
G01D02*
G03X25985I8268J0D01*
G01D02*
G03X9449I-8268J0D01*
G01D02*
G03X25985I8268J0D01*
G01D02*
G03X9449I-8268J0D01*
G01D02*
G03X25985I8268J0D01*
G01X9449D02*
G03X25985I8268J0D01*
G01D02*
G03X9449I-8268J0D01*
G01D02*
G03X25985I8268J0D01*
G01D02*
G03X9449I-8268J0D01*
G01X3937Y69685D02*
X173229D01*
G01X0Y73622D02*
G03X3937Y69685I3937J0D01*
G01X0Y127559D02*
Y73622D01*
G01X3937Y61811D02*
G03X0Y57874I0J-3937D01*
G01X173229Y61811D02*
X3937D01*
G01X37008Y139370D02*
G03Y131496I0J-3937D01*
G01X11811D02*
G03Y139370I0J3937D01*
G01X25985Y159055D02*
G03X9449I-8268J0D01*
G01D02*
G03X25985I8268J0D01*
G01D02*
G03X9449I-8268J0D01*
G01D02*
G03X25985I8268J0D01*
G01D02*
G03X9449I-8268J0D01*
G01D02*
G03X25985I8268J0D01*
G01D02*
G03X9449I-8268J0D01*
G01D02*
G03X25985I8268J0D01*
G01X9449D02*
G03X25985I8268J0D01*
G01D02*
G03X9449I-8268J0D01*
G01D02*
G03X25985I8268J0D01*
G01D02*
G03X9449I-8268J0D01*
G01X3937Y139370D02*
X173229D01*
G01X0Y143307D02*
G03X3937Y139370I3937J0D01*
G01X0Y197244D02*
Y143307D01*
G01X3937Y131496D02*
G03X0Y127559I0J-3937D01*
G01X173229Y131496D02*
X3937D01*
G01X37008Y278740D02*
G03Y270866I0J-3937D01*
G01X11811D02*
G03Y278740I0J3937D01*
G01X37008Y209055D02*
G03Y201181I0J-3937D01*
G01X11811D02*
G03Y209055I0J3937D01*
G01X3937Y278740D02*
X173229D01*
G01X0Y282677D02*
G03X3937Y278740I3937J0D01*
G01X25985Y228740D02*
G03X9449I-8268J0D01*
G01D02*
G03X25985I8268J0D01*
G01D02*
G03X9449I-8268J0D01*
G01D02*
G03X25985I8268J0D01*
G01D02*
G03X9449I-8268J0D01*
G01D02*
G03X25985I8268J0D01*
G01D02*
G03X9449I-8268J0D01*
G01D02*
G03X25985I8268J0D01*
G01X9449D02*
G03X25985I8268J0D01*
G01D02*
G03X9449I-8268J0D01*
G01D02*
G03X25985I8268J0D01*
G01D02*
G03X9449I-8268J0D01*
G01X3937Y209055D02*
X173229D01*
G01X0Y212992D02*
G03X3937Y209055I3937J0D01*
G01X0Y266929D02*
Y212992D01*
G01X3937Y270866D02*
G03X0Y266929I0J-3937D01*
G01X173229Y270866D02*
X3937D01*
G01Y201181D02*
G03X0Y197244I0J-3937D01*
G01X173229Y201181D02*
X3937D01*
G01X37008Y348425D02*
G03Y340551I0J-3937D01*
G01X11811D02*
G03Y348425I0J3937D01*
G01X9449Y368110D02*
G03X25985I8268J0D01*
G01X9449D02*
G03X25985I8268J0D01*
G01X9449D02*
G03X25985I8268J0D01*
G01X9449D02*
G03X25985I8268J0D01*
G01X9449D02*
G03X25985I8268J0D01*
G01X9449D02*
G03X25985I8268J0D01*
G01X3937Y348425D02*
X173229D01*
G01X0Y352362D02*
G03X3937Y348425I3937J0D01*
G01X0Y406299D02*
Y352362D01*
G01X25985Y298425D02*
G03X9449I-8268J0D01*
G01D02*
G03X25985I8268J0D01*
G01D02*
G03X9449I-8268J0D01*
G01D02*
G03X25985I8268J0D01*
G01D02*
G03X9449I-8268J0D01*
G01D02*
G03X25985I8268J0D01*
G01D02*
G03X9449I-8268J0D01*
G01D02*
G03X25985I8268J0D01*
G01X9449D02*
G03X25985I8268J0D01*
G01D02*
G03X9449I-8268J0D01*
G01D02*
G03X25985I8268J0D01*
G01D02*
G03X9449I-8268J0D01*
G01X0Y336614D02*
Y282677D01*
G01X3937Y340551D02*
G03X0Y336614I0J-3937D01*
G01X173229Y340551D02*
X3937D01*
G01X37008Y418110D02*
G03Y410236I0J-3937D01*
G01X11811D02*
G03Y418110I0J3937D01*
G01X25985Y437795D02*
G03X9449I-8268J0D01*
G01D02*
G03X25985I8268J0D01*
G01D02*
G03X9449I-8268J0D01*
G01D02*
G03X25985I8268J0D01*
G01D02*
G03X9449I-8268J0D01*
G01D02*
G03X25985I8268J0D01*
G01D02*
G03X9449I-8268J0D01*
G01D02*
G03X25985I8268J0D01*
G01X9449D02*
G03X25985I8268J0D01*
G01D02*
G03X9449I-8268J0D01*
G01D02*
G03X25985I8268J0D01*
G01D02*
G03X9449I-8268J0D01*
G01X3937Y418110D02*
X173229D01*
G01X0Y422047D02*
G03X3937Y418110I3937J0D01*
G01X0Y475984D02*
Y422047D01*
G01X25985Y368110D02*
G03X9449I-8268J0D01*
G01X25985D02*
G03X9449I-8268J0D01*
G01X25985D02*
G03X9449I-8268J0D01*
G01X25985D02*
G03X9449I-8268J0D01*
G01X25985D02*
G03X9449I-8268J0D01*
G01X25985D02*
G03X9449I-8268J0D01*
G01X3937Y410236D02*
G03X0Y406299I0J-3937D01*
G01X173229Y410236D02*
X3937D01*
G01X37008Y487795D02*
G03Y479921I0J-3937D01*
G01X11811D02*
G03Y487795I0J3937D01*
G01X25985Y507480D02*
G03X9449I-8268J0D01*
G01D02*
G03X25985I8268J0D01*
G01D02*
G03X9449I-8268J0D01*
G01D02*
G03X25985I8268J0D01*
G01D02*
G03X9449I-8268J0D01*
G01D02*
G03X25985I8268J0D01*
G01D02*
G03X9449I-8268J0D01*
G01D02*
G03X25985I8268J0D01*
G01X9449D02*
G03X25985I8268J0D01*
G01D02*
G03X9449I-8268J0D01*
G01D02*
G03X25985I8268J0D01*
G01D02*
G03X9449I-8268J0D01*
G01X3937Y487795D02*
X173229D01*
G01X0Y491732D02*
G03X3937Y487795I3937J0D01*
G01X0Y545669D02*
Y491732D01*
G01X3937Y479921D02*
G03X0Y475984I0J-3937D01*
G01X173229Y479921D02*
X3937D01*
G01X37008Y557480D02*
G03Y549606I0J-3937D01*
G01X11811D02*
G03Y557480I0J3937D01*
G01X25985Y577165D02*
G03X9449I-8268J0D01*
G01D02*
G03X25985I8268J0D01*
G01D02*
G03X9449I-8268J0D01*
G01D02*
G03X25985I8268J0D01*
G01D02*
G03X9449I-8268J0D01*
G01D02*
G03X25985I8268J0D01*
G01D02*
G03X9449I-8268J0D01*
G01D02*
G03X25985I8268J0D01*
G01X9449D02*
G03X25985I8268J0D01*
G01D02*
G03X9449I-8268J0D01*
G01D02*
G03X25985I8268J0D01*
G01D02*
G03X9449I-8268J0D01*
G01X3937Y557480D02*
X173229D01*
G01X0Y561417D02*
G03X3937Y557480I3937J0D01*
G01X0Y615354D02*
Y561417D01*
G01X3937Y549606D02*
G03X0Y545669I0J-3937D01*
G01X173229Y549606D02*
X3937D01*
G01X37008Y627165D02*
G03Y619291I0J-3937D01*
G01X11811D02*
G03Y627165I0J3937D01*
G01X25985Y646850D02*
G03X9449I-8268J0D01*
G01D02*
G03X25985I8268J0D01*
G01D02*
G03X9449I-8268J0D01*
G01D02*
G03X25985I8268J0D01*
G01D02*
G03X9449I-8268J0D01*
G01D02*
G03X25985I8268J0D01*
G01D02*
G03X9449I-8268J0D01*
G01D02*
G03X25985I8268J0D01*
G01X9449D02*
G03X25985I8268J0D01*
G01D02*
G03X9449I-8268J0D01*
G01D02*
G03X25985I8268J0D01*
G01D02*
G03X9449I-8268J0D01*
G01X3937Y627165D02*
X173229D01*
G01X0Y631102D02*
G03X3937Y627165I3937J0D01*
G01X0Y685039D02*
Y631102D01*
G01X3937Y688976D02*
G03X0Y685039I0J-3937D01*
G01X173229Y688976D02*
X3937D01*
G01Y619291D02*
G03X0Y615354I0J-3937D01*
G01X173229Y619291D02*
X3937D01*
G01X37008Y-7874D02*
X140158D01*
G01X196851D02*
G03Y0I0J3937D01*
G01X189564Y-19685D02*
G03X181690I-3937J0D01*
G01X165355Y0D02*
G03Y-7874I0J-3937D01*
G01X140158D02*
G03Y0I0J3937D01*
G01X185040Y18307D02*
G03X177166I-3937J0D01*
G01X189564Y-19685D02*
X539370D01*
G01X165355Y-7874D02*
X196851D01*
G01X211024Y19685D02*
G03X194489I-8267J0D01*
G01D02*
G03X211024I8267J0D01*
G01D02*
G03X194489I-8267J0D01*
G01D02*
G03X211024I8267J0D01*
G01D02*
G03X194489I-8267J0D01*
G01D02*
G03X211024I8267J0D01*
G01D02*
G03X194489I-8267J0D01*
G01D02*
G03X211024I8267J0D01*
G01X194489D02*
G03X211024I8267J0D01*
G01D02*
G03X194489I-8267J0D01*
G01D02*
G03X211024I8267J0D01*
G01D02*
G03X194489I-8267J0D01*
G01X188977Y0D02*
X358268D01*
G01X185040Y3937D02*
G03X188977Y0I3937J0D01*
G01X185040Y57874D02*
Y3937D01*
G01X167717Y19685D02*
G03X151181I-8268J0D01*
G01D02*
G03X167717I8268J0D01*
G01D02*
G03X151181I-8268J0D01*
G01D02*
G03X167717I8268J0D01*
G01D02*
G03X151181I-8268J0D01*
G01D02*
G03X167717I8268J0D01*
G01D02*
G03X151181I-8268J0D01*
G01D02*
G03X167717I8268J0D01*
G01X151181D02*
G03X167717I8268J0D01*
G01D02*
G03X151181I-8268J0D01*
G01D02*
G03X167717I8268J0D01*
G01D02*
G03X151181I-8268J0D01*
G01X177166Y3937D02*
Y57874D01*
G01X173229Y0D02*
G03X177166Y3937I0J3937D01*
G01X185040Y87992D02*
G03X177166I-3937J0D01*
G01Y113189D02*
G03X185040I3937J0D01*
G01X196851Y61811D02*
G03Y69685I0J3937D01*
G01X165355D02*
G03Y61811I0J-3937D01*
G01X140158D02*
G03Y69685I0J3937D01*
G01X177166Y43504D02*
G03X185040I3937J0D01*
G01X167717Y89370D02*
G03X151181I-8268J0D01*
G01D02*
G03X167717I8268J0D01*
G01D02*
G03X151181I-8268J0D01*
G01D02*
G03X167717I8268J0D01*
G01D02*
G03X151181I-8268J0D01*
G01D02*
G03X167717I8268J0D01*
G01D02*
G03X151181I-8268J0D01*
G01D02*
G03X167717I8268J0D01*
G01X151181D02*
G03X167717I8268J0D01*
G01D02*
G03X151181I-8268J0D01*
G01D02*
G03X167717I8268J0D01*
G01D02*
G03X151181I-8268J0D01*
G01X177166Y73622D02*
Y127559D01*
G01X173229Y69685D02*
G03X177166Y73622I0J3937D01*
G01X211024Y89370D02*
G03X194489I-8267J0D01*
G01D02*
G03X211024I8267J0D01*
G01D02*
G03X194489I-8267J0D01*
G01D02*
G03X211024I8267J0D01*
G01D02*
G03X194489I-8267J0D01*
G01D02*
G03X211024I8267J0D01*
G01D02*
G03X194489I-8267J0D01*
G01D02*
G03X211024I8267J0D01*
G01X194489D02*
G03X211024I8267J0D01*
G01D02*
G03X194489I-8267J0D01*
G01D02*
G03X211024I8267J0D01*
G01D02*
G03X194489I-8267J0D01*
G01X188977Y69685D02*
X358268D01*
G01X185040Y73622D02*
G03X188977Y69685I3937J0D01*
G01X185040Y127559D02*
Y73622D01*
G01X188977Y61811D02*
G03X185040Y57874I0J-3937D01*
G01X358268Y61811D02*
X188977D01*
G01X177166Y57874D02*
G03X173229Y61811I-3937J0D01*
G01X185040Y157677D02*
G03X177166I-3937J0D01*
G01Y182874D02*
G03X185040I3937J0D01*
G01X196851Y131496D02*
G03Y139370I0J3937D01*
G01X165355D02*
G03Y131496I0J-3937D01*
G01X140158D02*
G03Y139370I0J3937D01*
G01X167717Y159055D02*
G03X151181I-8268J0D01*
G01D02*
G03X167717I8268J0D01*
G01D02*
G03X151181I-8268J0D01*
G01D02*
G03X167717I8268J0D01*
G01D02*
G03X151181I-8268J0D01*
G01D02*
G03X167717I8268J0D01*
G01D02*
G03X151181I-8268J0D01*
G01D02*
G03X167717I8268J0D01*
G01X151181D02*
G03X167717I8268J0D01*
G01D02*
G03X151181I-8268J0D01*
G01D02*
G03X167717I8268J0D01*
G01D02*
G03X151181I-8268J0D01*
G01X177166Y143307D02*
Y197244D01*
G01X173229Y139370D02*
G03X177166Y143307I0J3937D01*
G01Y127559D02*
G03X173229Y131496I-3937J0D01*
G01X211024Y159055D02*
G03X194489I-8267J0D01*
G01D02*
G03X211024I8267J0D01*
G01D02*
G03X194489I-8267J0D01*
G01D02*
G03X211024I8267J0D01*
G01D02*
G03X194489I-8267J0D01*
G01D02*
G03X211024I8267J0D01*
G01D02*
G03X194489I-8267J0D01*
G01D02*
G03X211024I8267J0D01*
G01X194489D02*
G03X211024I8267J0D01*
G01D02*
G03X194489I-8267J0D01*
G01D02*
G03X211024I8267J0D01*
G01D02*
G03X194489I-8267J0D01*
G01X188977Y139370D02*
X358268D01*
G01X185040Y143307D02*
G03X188977Y139370I3937J0D01*
G01X185040Y197244D02*
Y143307D01*
G01X188977Y131496D02*
G03X185040Y127559I0J-3937D01*
G01X358268Y131496D02*
X188977D01*
G01X185040Y227362D02*
G03X177166I-3937J0D01*
G01Y252559D02*
G03X185040I3937J0D01*
G01X196851Y270866D02*
G03Y278740I0J3937D01*
G01X165355D02*
G03Y270866I0J-3937D01*
G01X140158D02*
G03Y278740I0J3937D01*
G01X196851Y201181D02*
G03Y209055I0J3937D01*
G01X165355D02*
G03Y201181I0J-3937D01*
G01X140158D02*
G03Y209055I0J3937D01*
G01X173229Y278740D02*
G03X177166Y282677I0J3937D01*
G01X188977Y278740D02*
X358268D01*
G01X185040Y282677D02*
G03X188977Y278740I3937J0D01*
G01X167717Y228740D02*
G03X151181I-8268J0D01*
G01D02*
G03X167717I8268J0D01*
G01D02*
G03X151181I-8268J0D01*
G01D02*
G03X167717I8268J0D01*
G01D02*
G03X151181I-8268J0D01*
G01D02*
G03X167717I8268J0D01*
G01D02*
G03X151181I-8268J0D01*
G01D02*
G03X167717I8268J0D01*
G01X151181D02*
G03X167717I8268J0D01*
G01D02*
G03X151181I-8268J0D01*
G01D02*
G03X167717I8268J0D01*
G01D02*
G03X151181I-8268J0D01*
G01X177166Y212992D02*
Y266929D01*
G01X173229Y209055D02*
G03X177166Y212992I0J3937D01*
G01Y266929D02*
G03X173229Y270866I-3937J0D01*
G01X211024Y228740D02*
G03X194489I-8267J0D01*
G01D02*
G03X211024I8267J0D01*
G01D02*
G03X194489I-8267J0D01*
G01D02*
G03X211024I8267J0D01*
G01D02*
G03X194489I-8267J0D01*
G01D02*
G03X211024I8267J0D01*
G01D02*
G03X194489I-8267J0D01*
G01D02*
G03X211024I8267J0D01*
G01X194489D02*
G03X211024I8267J0D01*
G01D02*
G03X194489I-8267J0D01*
G01D02*
G03X211024I8267J0D01*
G01D02*
G03X194489I-8267J0D01*
G01X188977Y209055D02*
X358268D01*
G01X185040Y212992D02*
G03X188977Y209055I3937J0D01*
G01X185040Y266929D02*
Y212992D01*
G01X188977Y270866D02*
G03X185040Y266929I0J-3937D01*
G01X358268Y270866D02*
X188977D01*
G01X177166Y197244D02*
G03X173229Y201181I-3937J0D01*
G01X188977D02*
G03X185040Y197244I0J-3937D01*
G01X358268Y201181D02*
X188977D01*
G01X185040Y297047D02*
G03X177166I-3937J0D01*
G01Y322244D02*
G03X185040I3937J0D01*
G01X196851Y340551D02*
G03Y348425I0J3937D01*
G01X165355D02*
G03Y340551I0J-3937D01*
G01X140158D02*
G03Y348425I0J3937D01*
G01X151181Y368110D02*
G03X167717I8268J0D01*
G01X151181D02*
G03X167717I8268J0D01*
G01X151181D02*
G03X167717I8268J0D01*
G01X151181D02*
G03X167717I8268J0D01*
G01X151181D02*
G03X167717I8268J0D01*
G01X151181D02*
G03X167717I8268J0D01*
G01X177166Y352362D02*
Y406299D01*
G01X173229Y348425D02*
G03X177166Y352362I0J3937D01*
G01X194489Y368110D02*
G03X211024I8267J0D01*
G01X194489D02*
G03X211024I8267J0D01*
G01X194489D02*
G03X211024I8267J0D01*
G01X194489D02*
G03X211024I8267J0D01*
G01X194489D02*
G03X211024I8267J0D01*
G01X194489D02*
G03X211024I8267J0D01*
G01X188977Y348425D02*
X358268D01*
G01X185040Y352362D02*
G03X188977Y348425I3937J0D01*
G01X185040Y406299D02*
Y352362D01*
G01X167717Y298425D02*
G03X151181I-8268J0D01*
G01D02*
G03X167717I8268J0D01*
G01D02*
G03X151181I-8268J0D01*
G01D02*
G03X167717I8268J0D01*
G01D02*
G03X151181I-8268J0D01*
G01D02*
G03X167717I8268J0D01*
G01D02*
G03X151181I-8268J0D01*
G01D02*
G03X167717I8268J0D01*
G01X151181D02*
G03X167717I8268J0D01*
G01D02*
G03X151181I-8268J0D01*
G01D02*
G03X167717I8268J0D01*
G01D02*
G03X151181I-8268J0D01*
G01X177166Y282677D02*
Y336614D01*
G01D02*
G03X173229Y340551I-3937J0D01*
G01X211024Y298425D02*
G03X194489I-8267J0D01*
G01D02*
G03X211024I8267J0D01*
G01D02*
G03X194489I-8267J0D01*
G01D02*
G03X211024I8267J0D01*
G01D02*
G03X194489I-8267J0D01*
G01D02*
G03X211024I8267J0D01*
G01D02*
G03X194489I-8267J0D01*
G01D02*
G03X211024I8267J0D01*
G01X194489D02*
G03X211024I8267J0D01*
G01D02*
G03X194489I-8267J0D01*
G01D02*
G03X211024I8267J0D01*
G01D02*
G03X194489I-8267J0D01*
G01X185040Y336614D02*
Y282677D01*
G01X188977Y340551D02*
G03X185040Y336614I0J-3937D01*
G01X358268Y340551D02*
X188977D01*
G01X185040Y436417D02*
G03X177166I-3937J0D01*
G01X185040Y366732D02*
G03X177166I-3937J0D01*
G01Y391929D02*
G03X185040I3937J0D01*
G01X196851Y410236D02*
G03Y418110I0J3937D01*
G01X165355D02*
G03Y410236I0J-3937D01*
G01X140158D02*
G03Y418110I0J3937D01*
G01X167717Y437795D02*
G03X151181I-8268J0D01*
G01D02*
G03X167717I8268J0D01*
G01D02*
G03X151181I-8268J0D01*
G01D02*
G03X167717I8268J0D01*
G01D02*
G03X151181I-8268J0D01*
G01D02*
G03X167717I8268J0D01*
G01D02*
G03X151181I-8268J0D01*
G01D02*
G03X167717I8268J0D01*
G01X151181D02*
G03X167717I8268J0D01*
G01D02*
G03X151181I-8268J0D01*
G01D02*
G03X167717I8268J0D01*
G01D02*
G03X151181I-8268J0D01*
G01X177166Y422047D02*
Y475984D01*
G01X173229Y418110D02*
G03X177166Y422047I0J3937D01*
G01X211024Y437795D02*
G03X194489I-8267J0D01*
G01D02*
G03X211024I8267J0D01*
G01D02*
G03X194489I-8267J0D01*
G01D02*
G03X211024I8267J0D01*
G01D02*
G03X194489I-8267J0D01*
G01D02*
G03X211024I8267J0D01*
G01D02*
G03X194489I-8267J0D01*
G01D02*
G03X211024I8267J0D01*
G01X194489D02*
G03X211024I8267J0D01*
G01D02*
G03X194489I-8267J0D01*
G01D02*
G03X211024I8267J0D01*
G01D02*
G03X194489I-8267J0D01*
G01X188977Y418110D02*
X358268D01*
G01X185040Y422047D02*
G03X188977Y418110I3937J0D01*
G01X185040Y475984D02*
Y422047D01*
G01X167717Y368110D02*
G03X151181I-8268J0D01*
G01X167717D02*
G03X151181I-8268J0D01*
G01X167717D02*
G03X151181I-8268J0D01*
G01X167717D02*
G03X151181I-8268J0D01*
G01X167717D02*
G03X151181I-8268J0D01*
G01X167717D02*
G03X151181I-8268J0D01*
G01X177166Y406299D02*
G03X173229Y410236I-3937J0D01*
G01X211024Y368110D02*
G03X194489I-8267J0D01*
G01X211024D02*
G03X194489I-8267J0D01*
G01X211024D02*
G03X194489I-8267J0D01*
G01X211024D02*
G03X194489I-8267J0D01*
G01X211024D02*
G03X194489I-8267J0D01*
G01X211024D02*
G03X194489I-8267J0D01*
G01X188977Y410236D02*
G03X185040Y406299I0J-3937D01*
G01X358268Y410236D02*
X188977D01*
G01X185040Y506102D02*
G03X177166I-3937J0D01*
G01Y531299D02*
G03X185040I3937J0D01*
G01X177166Y461614D02*
G03X185040I3937J0D01*
G01X196851Y479921D02*
G03Y487795I0J3937D01*
G01X165355D02*
G03Y479921I0J-3937D01*
G01X140158D02*
G03Y487795I0J3937D01*
G01X167717Y507480D02*
G03X151181I-8268J0D01*
G01D02*
G03X167717I8268J0D01*
G01D02*
G03X151181I-8268J0D01*
G01D02*
G03X167717I8268J0D01*
G01D02*
G03X151181I-8268J0D01*
G01D02*
G03X167717I8268J0D01*
G01D02*
G03X151181I-8268J0D01*
G01D02*
G03X167717I8268J0D01*
G01X151181D02*
G03X167717I8268J0D01*
G01D02*
G03X151181I-8268J0D01*
G01D02*
G03X167717I8268J0D01*
G01D02*
G03X151181I-8268J0D01*
G01X177166Y491732D02*
Y545669D01*
G01X173229Y487795D02*
G03X177166Y491732I0J3937D01*
G01X211024Y507480D02*
G03X194489I-8267J0D01*
G01D02*
G03X211024I8267J0D01*
G01D02*
G03X194489I-8267J0D01*
G01D02*
G03X211024I8267J0D01*
G01D02*
G03X194489I-8267J0D01*
G01D02*
G03X211024I8267J0D01*
G01D02*
G03X194489I-8267J0D01*
G01D02*
G03X211024I8267J0D01*
G01X194489D02*
G03X211024I8267J0D01*
G01D02*
G03X194489I-8267J0D01*
G01D02*
G03X211024I8267J0D01*
G01D02*
G03X194489I-8267J0D01*
G01X188977Y487795D02*
X358268D01*
G01X185040Y491732D02*
G03X188977Y487795I3937J0D01*
G01X185040Y545669D02*
Y491732D01*
G01X177166Y475984D02*
G03X173229Y479921I-3937J0D01*
G01X188977D02*
G03X185040Y475984I0J-3937D01*
G01X358268Y479921D02*
X188977D01*
G01X185040Y575787D02*
G03X177166I-3937J0D01*
G01Y600984D02*
G03X185040I3937J0D01*
G01X196851Y549606D02*
G03Y557480I0J3937D01*
G01X165355D02*
G03Y549606I0J-3937D01*
G01X140158D02*
G03Y557480I0J3937D01*
G01X167717Y577165D02*
G03X151181I-8268J0D01*
G01D02*
G03X167717I8268J0D01*
G01D02*
G03X151181I-8268J0D01*
G01D02*
G03X167717I8268J0D01*
G01D02*
G03X151181I-8268J0D01*
G01D02*
G03X167717I8268J0D01*
G01D02*
G03X151181I-8268J0D01*
G01D02*
G03X167717I8268J0D01*
G01X151181D02*
G03X167717I8268J0D01*
G01D02*
G03X151181I-8268J0D01*
G01D02*
G03X167717I8268J0D01*
G01D02*
G03X151181I-8268J0D01*
G01X177166Y561417D02*
Y615354D01*
G01X173229Y557480D02*
G03X177166Y561417I0J3937D01*
G01X211024Y577165D02*
G03X194489I-8267J0D01*
G01D02*
G03X211024I8267J0D01*
G01D02*
G03X194489I-8267J0D01*
G01D02*
G03X211024I8267J0D01*
G01D02*
G03X194489I-8267J0D01*
G01D02*
G03X211024I8267J0D01*
G01D02*
G03X194489I-8267J0D01*
G01D02*
G03X211024I8267J0D01*
G01X194489D02*
G03X211024I8267J0D01*
G01D02*
G03X194489I-8267J0D01*
G01D02*
G03X211024I8267J0D01*
G01D02*
G03X194489I-8267J0D01*
G01X188977Y557480D02*
X358268D01*
G01X185040Y561417D02*
G03X188977Y557480I3937J0D01*
G01X185040Y615354D02*
Y561417D01*
G01X177166Y545669D02*
G03X173229Y549606I-3937J0D01*
G01X188977D02*
G03X185040Y545669I0J-3937D01*
G01X358268Y549606D02*
X188977D01*
G01X185040Y645472D02*
G03X177166I-3937J0D01*
G01Y670669D02*
G03X185040I3937J0D01*
G01X196851Y619291D02*
G03Y627165I0J3937D01*
G01X165355D02*
G03Y619291I0J-3937D01*
G01X140158D02*
G03Y627165I0J3937D01*
G01X167717Y646850D02*
G03X151181I-8268J0D01*
G01D02*
G03X167717I8268J0D01*
G01D02*
G03X151181I-8268J0D01*
G01D02*
G03X167717I8268J0D01*
G01D02*
G03X151181I-8268J0D01*
G01D02*
G03X167717I8268J0D01*
G01D02*
G03X151181I-8268J0D01*
G01D02*
G03X167717I8268J0D01*
G01X151181D02*
G03X167717I8268J0D01*
G01D02*
G03X151181I-8268J0D01*
G01D02*
G03X167717I8268J0D01*
G01D02*
G03X151181I-8268J0D01*
G01X177166Y631102D02*
Y685039D01*
G01X173229Y627165D02*
G03X177166Y631102I0J3937D01*
G01Y685039D02*
G03X173229Y688976I-3937J0D01*
G01X211024Y646850D02*
G03X194489I-8267J0D01*
G01D02*
G03X211024I8267J0D01*
G01D02*
G03X194489I-8267J0D01*
G01D02*
G03X211024I8267J0D01*
G01D02*
G03X194489I-8267J0D01*
G01D02*
G03X211024I8267J0D01*
G01D02*
G03X194489I-8267J0D01*
G01D02*
G03X211024I8267J0D01*
G01X194489D02*
G03X211024I8267J0D01*
G01D02*
G03X194489I-8267J0D01*
G01D02*
G03X211024I8267J0D01*
G01D02*
G03X194489I-8267J0D01*
G01X188977Y627165D02*
X358268D01*
G01X185040Y631102D02*
G03X188977Y627165I3937J0D01*
G01X185040Y685039D02*
Y631102D01*
G01X188977Y688976D02*
G03X185040Y685039I0J-3937D01*
G01X358268Y688976D02*
X188977D01*
G01X177166Y615354D02*
G03X173229Y619291I-3937J0D01*
G01X188977D02*
G03X185040Y615354I0J-3937D01*
G01X358268Y619291D02*
X188977D01*
G01X222048Y0D02*
G03Y-7874I0J-3937D01*
G01D02*
X325197D01*
G01X222048Y69685D02*
G03Y61811I0J-3937D01*
G01Y139370D02*
G03Y131496I0J-3937D01*
G01Y278740D02*
G03Y270866I0J-3937D01*
G01Y209055D02*
G03Y201181I0J-3937D01*
G01Y348425D02*
G03Y340551I0J-3937D01*
G01Y418110D02*
G03Y410236I0J-3937D01*
G01Y487795D02*
G03Y479921I0J-3937D01*
G01Y557480D02*
G03Y549606I0J-3937D01*
G01Y627165D02*
G03Y619291I0J-3937D01*
G01X370079Y18307D02*
G03X362205I-3937J0D01*
G01X350394Y0D02*
G03Y-7874I0J-3937D01*
G01X325197D02*
G03Y0I0J3937D01*
G01X350394Y-7874D02*
X381890D01*
G01X352756Y19685D02*
G03X336221I-8267J0D01*
G01D02*
G03X352756I8268J0D01*
G01D02*
G03X336221I-8267J0D01*
G01D02*
G03X352756I8268J0D01*
G01D02*
G03X336221I-8267J0D01*
G01D02*
G03X352756I8268J0D01*
G01D02*
G03X336221I-8267J0D01*
G01D02*
G03X352756I8268J0D01*
G01X336221D02*
G03X352756I8268J0D01*
G01D02*
G03X336221I-8267J0D01*
G01D02*
G03X352756I8268J0D01*
G01D02*
G03X336221I-8267J0D01*
G01X362205Y3937D02*
Y57874D01*
G01X358268Y0D02*
G03X362205Y3937I0J3937D01*
G01X370079Y87992D02*
G03X362205I-3937J0D01*
G01Y113189D02*
G03X370079I3937J0D01*
G01X362205Y43504D02*
G03X370079I3937J0D01*
G01X350394Y69685D02*
G03Y61811I0J-3937D01*
G01X325197D02*
G03Y69685I0J3937D01*
G01X352756Y89370D02*
G03X336221I-8267J0D01*
G01D02*
G03X352756I8268J0D01*
G01D02*
G03X336221I-8267J0D01*
G01D02*
G03X352756I8268J0D01*
G01D02*
G03X336221I-8267J0D01*
G01D02*
G03X352756I8268J0D01*
G01D02*
G03X336221I-8267J0D01*
G01D02*
G03X352756I8268J0D01*
G01X336221D02*
G03X352756I8268J0D01*
G01D02*
G03X336221I-8267J0D01*
G01D02*
G03X352756I8268J0D01*
G01D02*
G03X336221I-8267J0D01*
G01X362205Y73622D02*
Y127559D01*
G01X358268Y69685D02*
G03X362205Y73622I0J3937D01*
G01Y57874D02*
G03X358268Y61811I-3937J0D01*
G01X370079Y157677D02*
G03X362205I-3937J0D01*
G01Y182874D02*
G03X370079I3937J0D01*
G01X350394Y139370D02*
G03Y131496I0J-3937D01*
G01X325197D02*
G03Y139370I0J3937D01*
G01X352756Y159055D02*
G03X336221I-8267J0D01*
G01D02*
G03X352756I8268J0D01*
G01D02*
G03X336221I-8267J0D01*
G01D02*
G03X352756I8268J0D01*
G01D02*
G03X336221I-8267J0D01*
G01D02*
G03X352756I8268J0D01*
G01D02*
G03X336221I-8267J0D01*
G01D02*
G03X352756I8268J0D01*
G01X336221D02*
G03X352756I8268J0D01*
G01D02*
G03X336221I-8267J0D01*
G01D02*
G03X352756I8268J0D01*
G01D02*
G03X336221I-8267J0D01*
G01X362205Y143307D02*
Y197244D01*
G01X358268Y139370D02*
G03X362205Y143307I0J3937D01*
G01Y127559D02*
G03X358268Y131496I-3937J0D01*
G01X370079Y227362D02*
G03X362205I-3937J0D01*
G01Y252559D02*
G03X370079I3937J0D01*
G01X350394Y278740D02*
G03Y270866I0J-3937D01*
G01X325197D02*
G03Y278740I0J3937D01*
G01X350394Y209055D02*
G03Y201181I0J-3937D01*
G01X325197D02*
G03Y209055I0J3937D01*
G01X358268Y278740D02*
G03X362205Y282677I0J3937D01*
G01X352756Y228740D02*
G03X336221I-8267J0D01*
G01D02*
G03X352756I8268J0D01*
G01D02*
G03X336221I-8267J0D01*
G01D02*
G03X352756I8268J0D01*
G01D02*
G03X336221I-8267J0D01*
G01D02*
G03X352756I8268J0D01*
G01D02*
G03X336221I-8267J0D01*
G01D02*
G03X352756I8268J0D01*
G01X336221D02*
G03X352756I8268J0D01*
G01D02*
G03X336221I-8267J0D01*
G01D02*
G03X352756I8268J0D01*
G01D02*
G03X336221I-8267J0D01*
G01X362205Y212992D02*
Y266929D01*
G01X358268Y209055D02*
G03X362205Y212992I0J3937D01*
G01Y266929D02*
G03X358268Y270866I-3937J0D01*
G01X362205Y197244D02*
G03X358268Y201181I-3937J0D01*
G01X370079Y297047D02*
G03X362205I-3937J0D01*
G01Y322244D02*
G03X370079I3937J0D01*
G01X350394Y348425D02*
G03Y340551I0J-3937D01*
G01X325197D02*
G03Y348425I0J3937D01*
G01X336221Y368110D02*
G03X352756I8268J0D01*
G01X336221D02*
G03X352756I8268J0D01*
G01X336221D02*
G03X352756I8268J0D01*
G01X336221D02*
G03X352756I8268J0D01*
G01X336221D02*
G03X352756I8268J0D01*
G01X336221D02*
G03X352756I8268J0D01*
G01X362205Y352362D02*
Y406299D01*
G01X358268Y348425D02*
G03X362205Y352362I0J3937D01*
G01X352756Y298425D02*
G03X336221I-8267J0D01*
G01D02*
G03X352756I8268J0D01*
G01D02*
G03X336221I-8267J0D01*
G01D02*
G03X352756I8268J0D01*
G01D02*
G03X336221I-8267J0D01*
G01D02*
G03X352756I8268J0D01*
G01D02*
G03X336221I-8267J0D01*
G01D02*
G03X352756I8268J0D01*
G01X336221D02*
G03X352756I8268J0D01*
G01D02*
G03X336221I-8267J0D01*
G01D02*
G03X352756I8268J0D01*
G01D02*
G03X336221I-8267J0D01*
G01X362205Y282677D02*
Y336614D01*
G01D02*
G03X358268Y340551I-3937J0D01*
G01X370079Y436417D02*
G03X362205I-3937J0D01*
G01X370079Y366732D02*
G03X362205I-3937J0D01*
G01Y391929D02*
G03X370079I3937J0D01*
G01X350394Y418110D02*
G03Y410236I0J-3937D01*
G01X325197D02*
G03Y418110I0J3937D01*
G01X352756Y437795D02*
G03X336221I-8267J0D01*
G01D02*
G03X352756I8268J0D01*
G01D02*
G03X336221I-8267J0D01*
G01D02*
G03X352756I8268J0D01*
G01D02*
G03X336221I-8267J0D01*
G01D02*
G03X352756I8268J0D01*
G01D02*
G03X336221I-8267J0D01*
G01D02*
G03X352756I8268J0D01*
G01X336221D02*
G03X352756I8268J0D01*
G01D02*
G03X336221I-8267J0D01*
G01D02*
G03X352756I8268J0D01*
G01D02*
G03X336221I-8267J0D01*
G01X362205Y422047D02*
Y475984D01*
G01X358268Y418110D02*
G03X362205Y422047I0J3937D01*
G01X352756Y368110D02*
G03X336221I-8267J0D01*
G01X352756D02*
G03X336221I-8267J0D01*
G01X352756D02*
G03X336221I-8267J0D01*
G01X352756D02*
G03X336221I-8267J0D01*
G01X352756D02*
G03X336221I-8267J0D01*
G01X352756D02*
G03X336221I-8267J0D01*
G01X362205Y406299D02*
G03X358268Y410236I-3937J0D01*
G01X370079Y506102D02*
G03X362205I-3937J0D01*
G01Y531299D02*
G03X370079I3937J0D01*
G01X362205Y461614D02*
G03X370079I3937J0D01*
G01X350394Y487795D02*
G03Y479921I0J-3937D01*
G01X325197D02*
G03Y487795I0J3937D01*
G01X352756Y507480D02*
G03X336221I-8267J0D01*
G01D02*
G03X352756I8268J0D01*
G01D02*
G03X336221I-8267J0D01*
G01D02*
G03X352756I8268J0D01*
G01D02*
G03X336221I-8267J0D01*
G01D02*
G03X352756I8268J0D01*
G01D02*
G03X336221I-8267J0D01*
G01D02*
G03X352756I8268J0D01*
G01X336221D02*
G03X352756I8268J0D01*
G01D02*
G03X336221I-8267J0D01*
G01D02*
G03X352756I8268J0D01*
G01D02*
G03X336221I-8267J0D01*
G01X362205Y491732D02*
Y545669D01*
G01X358268Y487795D02*
G03X362205Y491732I0J3937D01*
G01Y475984D02*
G03X358268Y479921I-3937J0D01*
G01X370079Y575787D02*
G03X362205I-3937J0D01*
G01Y600984D02*
G03X370079I3937J0D01*
G01X350394Y557480D02*
G03Y549606I0J-3937D01*
G01X325197D02*
G03Y557480I0J3937D01*
G01X352756Y577165D02*
G03X336221I-8267J0D01*
G01D02*
G03X352756I8268J0D01*
G01D02*
G03X336221I-8267J0D01*
G01D02*
G03X352756I8268J0D01*
G01D02*
G03X336221I-8267J0D01*
G01D02*
G03X352756I8268J0D01*
G01D02*
G03X336221I-8267J0D01*
G01D02*
G03X352756I8268J0D01*
G01X336221D02*
G03X352756I8268J0D01*
G01D02*
G03X336221I-8267J0D01*
G01D02*
G03X352756I8268J0D01*
G01D02*
G03X336221I-8267J0D01*
G01X362205Y561417D02*
Y615354D01*
G01X358268Y557480D02*
G03X362205Y561417I0J3937D01*
G01Y545669D02*
G03X358268Y549606I-3937J0D01*
G01X370079Y645472D02*
G03X362205I-3937J0D01*
G01Y670669D02*
G03X370079I3937J0D01*
G01X350394Y627165D02*
G03Y619291I0J-3937D01*
G01X325197D02*
G03Y627165I0J3937D01*
G01X352756Y646850D02*
G03X336221I-8267J0D01*
G01D02*
G03X352756I8268J0D01*
G01D02*
G03X336221I-8267J0D01*
G01D02*
G03X352756I8268J0D01*
G01D02*
G03X336221I-8267J0D01*
G01D02*
G03X352756I8268J0D01*
G01D02*
G03X336221I-8267J0D01*
G01D02*
G03X352756I8268J0D01*
G01X336221D02*
G03X352756I8268J0D01*
G01D02*
G03X336221I-8267J0D01*
G01D02*
G03X352756I8268J0D01*
G01D02*
G03X336221I-8267J0D01*
G01X362205Y631102D02*
Y685039D01*
G01X358268Y627165D02*
G03X362205Y631102I0J3937D01*
G01Y685039D02*
G03X358268Y688976I-3937J0D01*
G01X362205Y615354D02*
G03X358268Y619291I-3937J0D01*
G01X407087Y0D02*
G03Y-7874I0J-3937D01*
G01X381890D02*
G03Y0I0J3937D01*
G01X407087Y-7874D02*
X510237D01*
G01X396063Y19685D02*
G03X379528I-8268J0D01*
G01D02*
G03X396063I8267J0D01*
G01D02*
G03X379528I-8268J0D01*
G01D02*
G03X396063I8267J0D01*
G01D02*
G03X379528I-8268J0D01*
G01D02*
G03X396063I8267J0D01*
G01D02*
G03X379528I-8268J0D01*
G01D02*
G03X396063I8267J0D01*
G01X379528D02*
G03X396063I8267J0D01*
G01D02*
G03X379528I-8268J0D01*
G01D02*
G03X396063I8267J0D01*
G01D02*
G03X379528I-8268J0D01*
G01X374016Y0D02*
X543307D01*
G01X370079Y3937D02*
G03X374016Y0I3937J0D01*
G01X370079Y57874D02*
Y3937D01*
G01X407087Y69685D02*
G03Y61811I0J-3937D01*
G01X381890D02*
G03Y69685I0J3937D01*
G01X396063Y89370D02*
G03X379528I-8268J0D01*
G01D02*
G03X396063I8267J0D01*
G01D02*
G03X379528I-8268J0D01*
G01D02*
G03X396063I8267J0D01*
G01D02*
G03X379528I-8268J0D01*
G01D02*
G03X396063I8267J0D01*
G01D02*
G03X379528I-8268J0D01*
G01D02*
G03X396063I8267J0D01*
G01X379528D02*
G03X396063I8267J0D01*
G01D02*
G03X379528I-8268J0D01*
G01D02*
G03X396063I8267J0D01*
G01D02*
G03X379528I-8268J0D01*
G01X374016Y69685D02*
X543307D01*
G01X370079Y73622D02*
G03X374016Y69685I3937J0D01*
G01X370079Y127559D02*
Y73622D01*
G01X374016Y61811D02*
G03X370079Y57874I0J-3937D01*
G01X543307Y61811D02*
X374016D01*
G01X407087Y139370D02*
G03Y131496I0J-3937D01*
G01X381890D02*
G03Y139370I0J3937D01*
G01X396063Y159055D02*
G03X379528I-8268J0D01*
G01D02*
G03X396063I8267J0D01*
G01D02*
G03X379528I-8268J0D01*
G01D02*
G03X396063I8267J0D01*
G01D02*
G03X379528I-8268J0D01*
G01D02*
G03X396063I8267J0D01*
G01D02*
G03X379528I-8268J0D01*
G01D02*
G03X396063I8267J0D01*
G01X379528D02*
G03X396063I8267J0D01*
G01D02*
G03X379528I-8268J0D01*
G01D02*
G03X396063I8267J0D01*
G01D02*
G03X379528I-8268J0D01*
G01X374016Y139370D02*
X543307D01*
G01X370079Y143307D02*
G03X374016Y139370I3937J0D01*
G01X370079Y197244D02*
Y143307D01*
G01X374016Y131496D02*
G03X370079Y127559I0J-3937D01*
G01X543307Y131496D02*
X374016D01*
G01X407087Y278740D02*
G03Y270866I0J-3937D01*
G01X381890D02*
G03Y278740I0J3937D01*
G01X407087Y209055D02*
G03Y201181I0J-3937D01*
G01X381890D02*
G03Y209055I0J3937D01*
G01X374016Y278740D02*
X543307D01*
G01X370079Y282677D02*
G03X374016Y278740I3937J0D01*
G01X396063Y228740D02*
G03X379528I-8268J0D01*
G01D02*
G03X396063I8267J0D01*
G01D02*
G03X379528I-8268J0D01*
G01D02*
G03X396063I8267J0D01*
G01D02*
G03X379528I-8268J0D01*
G01D02*
G03X396063I8267J0D01*
G01D02*
G03X379528I-8268J0D01*
G01D02*
G03X396063I8267J0D01*
G01X379528D02*
G03X396063I8267J0D01*
G01D02*
G03X379528I-8268J0D01*
G01D02*
G03X396063I8267J0D01*
G01D02*
G03X379528I-8268J0D01*
G01X374016Y209055D02*
X543307D01*
G01X370079Y212992D02*
G03X374016Y209055I3937J0D01*
G01X370079Y266929D02*
Y212992D01*
G01X374016Y270866D02*
G03X370079Y266929I0J-3937D01*
G01X543307Y270866D02*
X374016D01*
G01Y201181D02*
G03X370079Y197244I0J-3937D01*
G01X543307Y201181D02*
X374016D01*
G01X407087Y348425D02*
G03Y340551I0J-3937D01*
G01X381890D02*
G03Y348425I0J3937D01*
G01X379528Y368110D02*
G03X396063I8267J0D01*
G01X379528D02*
G03X396063I8267J0D01*
G01X379528D02*
G03X396063I8267J0D01*
G01X379528D02*
G03X396063I8267J0D01*
G01X379528D02*
G03X396063I8267J0D01*
G01X379528D02*
G03X396063I8267J0D01*
G01X374016Y348425D02*
X543307D01*
G01X370079Y352362D02*
G03X374016Y348425I3937J0D01*
G01X370079Y406299D02*
Y352362D01*
G01X396063Y298425D02*
G03X379528I-8268J0D01*
G01D02*
G03X396063I8267J0D01*
G01D02*
G03X379528I-8268J0D01*
G01D02*
G03X396063I8267J0D01*
G01D02*
G03X379528I-8268J0D01*
G01D02*
G03X396063I8267J0D01*
G01D02*
G03X379528I-8268J0D01*
G01D02*
G03X396063I8267J0D01*
G01X379528D02*
G03X396063I8267J0D01*
G01D02*
G03X379528I-8268J0D01*
G01D02*
G03X396063I8267J0D01*
G01D02*
G03X379528I-8268J0D01*
G01X370079Y336614D02*
Y282677D01*
G01X374016Y340551D02*
G03X370079Y336614I0J-3937D01*
G01X543307Y340551D02*
X374016D01*
G01X407087Y418110D02*
G03Y410236I0J-3937D01*
G01X381890D02*
G03Y418110I0J3937D01*
G01X396063Y437795D02*
G03X379528I-8268J0D01*
G01D02*
G03X396063I8267J0D01*
G01D02*
G03X379528I-8268J0D01*
G01D02*
G03X396063I8267J0D01*
G01D02*
G03X379528I-8268J0D01*
G01D02*
G03X396063I8267J0D01*
G01D02*
G03X379528I-8268J0D01*
G01D02*
G03X396063I8267J0D01*
G01X379528D02*
G03X396063I8267J0D01*
G01D02*
G03X379528I-8268J0D01*
G01D02*
G03X396063I8267J0D01*
G01D02*
G03X379528I-8268J0D01*
G01X374016Y418110D02*
X543307D01*
G01X370079Y422047D02*
G03X374016Y418110I3937J0D01*
G01X370079Y475984D02*
Y422047D01*
G01X396063Y368110D02*
G03X379528I-8268J0D01*
G01X396063D02*
G03X379528I-8268J0D01*
G01X396063D02*
G03X379528I-8268J0D01*
G01X396063D02*
G03X379528I-8268J0D01*
G01X396063D02*
G03X379528I-8268J0D01*
G01X396063D02*
G03X379528I-8268J0D01*
G01X374016Y410236D02*
G03X370079Y406299I0J-3937D01*
G01X543307Y410236D02*
X374016D01*
G01X407087Y487795D02*
G03Y479921I0J-3937D01*
G01X381890D02*
G03Y487795I0J3937D01*
G01X396063Y507480D02*
G03X379528I-8268J0D01*
G01D02*
G03X396063I8267J0D01*
G01D02*
G03X379528I-8268J0D01*
G01D02*
G03X396063I8267J0D01*
G01D02*
G03X379528I-8268J0D01*
G01D02*
G03X396063I8267J0D01*
G01D02*
G03X379528I-8268J0D01*
G01D02*
G03X396063I8267J0D01*
G01X379528D02*
G03X396063I8267J0D01*
G01D02*
G03X379528I-8268J0D01*
G01D02*
G03X396063I8267J0D01*
G01D02*
G03X379528I-8268J0D01*
G01X374016Y487795D02*
X543307D01*
G01X370079Y491732D02*
G03X374016Y487795I3937J0D01*
G01X370079Y545669D02*
Y491732D01*
G01X374016Y479921D02*
G03X370079Y475984I0J-3937D01*
G01X543307Y479921D02*
X374016D01*
G01X407087Y557480D02*
G03Y549606I0J-3937D01*
G01X381890D02*
G03Y557480I0J3937D01*
G01X396063Y577165D02*
G03X379528I-8268J0D01*
G01D02*
G03X396063I8267J0D01*
G01D02*
G03X379528I-8268J0D01*
G01D02*
G03X396063I8267J0D01*
G01D02*
G03X379528I-8268J0D01*
G01D02*
G03X396063I8267J0D01*
G01D02*
G03X379528I-8268J0D01*
G01D02*
G03X396063I8267J0D01*
G01X379528D02*
G03X396063I8267J0D01*
G01D02*
G03X379528I-8268J0D01*
G01D02*
G03X396063I8267J0D01*
G01D02*
G03X379528I-8268J0D01*
G01X374016Y557480D02*
X543307D01*
G01X370079Y561417D02*
G03X374016Y557480I3937J0D01*
G01X370079Y615354D02*
Y561417D01*
G01X374016Y549606D02*
G03X370079Y545669I0J-3937D01*
G01X543307Y549606D02*
X374016D01*
G01X407087Y627165D02*
G03Y619291I0J-3937D01*
G01X381890D02*
G03Y627165I0J3937D01*
G01X396063Y646850D02*
G03X379528I-8268J0D01*
G01D02*
G03X396063I8267J0D01*
G01D02*
G03X379528I-8268J0D01*
G01D02*
G03X396063I8267J0D01*
G01D02*
G03X379528I-8268J0D01*
G01D02*
G03X396063I8267J0D01*
G01D02*
G03X379528I-8268J0D01*
G01D02*
G03X396063I8267J0D01*
G01X379528D02*
G03X396063I8267J0D01*
G01D02*
G03X379528I-8268J0D01*
G01D02*
G03X396063I8267J0D01*
G01D02*
G03X379528I-8268J0D01*
G01X374016Y627165D02*
X543307D01*
G01X370079Y631102D02*
G03X374016Y627165I3937J0D01*
G01X370079Y685039D02*
Y631102D01*
G01X374016Y688976D02*
G03X370079Y685039I0J-3937D01*
G01X543307Y688976D02*
X374016D01*
G01Y619291D02*
G03X370079Y615354I0J-3937D01*
G01X543307Y619291D02*
X374016D01*
G01X510237Y-7874D02*
G03Y0I0J3937D01*
G01X537796Y19685D02*
G03X521260I-8268J0D01*
G01D02*
G03X537796I8268J0D01*
G01D02*
G03X521260I-8268J0D01*
G01D02*
G03X537796I8268J0D01*
G01D02*
G03X521260I-8268J0D01*
G01D02*
G03X537796I8268J0D01*
G01D02*
G03X521260I-8268J0D01*
G01D02*
G03X537796I8268J0D01*
G01X521260D02*
G03X537796I8268J0D01*
G01D02*
G03X521260I-8268J0D01*
G01D02*
G03X537796I8268J0D01*
G01D02*
G03X521260I-8268J0D01*
G01X510237Y61811D02*
G03Y69685I0J3937D01*
G01X537796Y89370D02*
G03X521260I-8268J0D01*
G01D02*
G03X537796I8268J0D01*
G01D02*
G03X521260I-8268J0D01*
G01D02*
G03X537796I8268J0D01*
G01D02*
G03X521260I-8268J0D01*
G01D02*
G03X537796I8268J0D01*
G01D02*
G03X521260I-8268J0D01*
G01D02*
G03X537796I8268J0D01*
G01X521260D02*
G03X537796I8268J0D01*
G01D02*
G03X521260I-8268J0D01*
G01D02*
G03X537796I8268J0D01*
G01D02*
G03X521260I-8268J0D01*
G01X510237Y131496D02*
G03Y139370I0J3937D01*
G01X537796Y159055D02*
G03X521260I-8268J0D01*
G01D02*
G03X537796I8268J0D01*
G01D02*
G03X521260I-8268J0D01*
G01D02*
G03X537796I8268J0D01*
G01D02*
G03X521260I-8268J0D01*
G01D02*
G03X537796I8268J0D01*
G01D02*
G03X521260I-8268J0D01*
G01D02*
G03X537796I8268J0D01*
G01X521260D02*
G03X537796I8268J0D01*
G01D02*
G03X521260I-8268J0D01*
G01D02*
G03X537796I8268J0D01*
G01D02*
G03X521260I-8268J0D01*
G01X510237Y270866D02*
G03Y278740I0J3937D01*
G01Y201181D02*
G03Y209055I0J3937D01*
G01X537796Y228740D02*
G03X521260I-8268J0D01*
G01D02*
G03X537796I8268J0D01*
G01D02*
G03X521260I-8268J0D01*
G01D02*
G03X537796I8268J0D01*
G01D02*
G03X521260I-8268J0D01*
G01D02*
G03X537796I8268J0D01*
G01D02*
G03X521260I-8268J0D01*
G01D02*
G03X537796I8268J0D01*
G01X521260D02*
G03X537796I8268J0D01*
G01D02*
G03X521260I-8268J0D01*
G01D02*
G03X537796I8268J0D01*
G01D02*
G03X521260I-8268J0D01*
G01X510237Y340551D02*
G03Y348425I0J3937D01*
G01X521260Y368110D02*
G03X537796I8268J0D01*
G01X521260D02*
G03X537796I8268J0D01*
G01X521260D02*
G03X537796I8268J0D01*
G01X521260D02*
G03X537796I8268J0D01*
G01X521260D02*
G03X537796I8268J0D01*
G01X521260D02*
G03X537796I8268J0D01*
G01Y298425D02*
G03X521260I-8268J0D01*
G01D02*
G03X537796I8268J0D01*
G01D02*
G03X521260I-8268J0D01*
G01D02*
G03X537796I8268J0D01*
G01D02*
G03X521260I-8268J0D01*
G01D02*
G03X537796I8268J0D01*
G01D02*
G03X521260I-8268J0D01*
G01D02*
G03X537796I8268J0D01*
G01X521260D02*
G03X537796I8268J0D01*
G01D02*
G03X521260I-8268J0D01*
G01D02*
G03X537796I8268J0D01*
G01D02*
G03X521260I-8268J0D01*
G01X510237Y410236D02*
G03Y418110I0J3937D01*
G01X537796Y437795D02*
G03X521260I-8268J0D01*
G01D02*
G03X537796I8268J0D01*
G01D02*
G03X521260I-8268J0D01*
G01D02*
G03X537796I8268J0D01*
G01D02*
G03X521260I-8268J0D01*
G01D02*
G03X537796I8268J0D01*
G01D02*
G03X521260I-8268J0D01*
G01D02*
G03X537796I8268J0D01*
G01X521260D02*
G03X537796I8268J0D01*
G01D02*
G03X521260I-8268J0D01*
G01D02*
G03X537796I8268J0D01*
G01D02*
G03X521260I-8268J0D01*
G01X537796Y368110D02*
G03X521260I-8268J0D01*
G01X537796D02*
G03X521260I-8268J0D01*
G01X537796D02*
G03X521260I-8268J0D01*
G01X537796D02*
G03X521260I-8268J0D01*
G01X537796D02*
G03X521260I-8268J0D01*
G01X537796D02*
G03X521260I-8268J0D01*
G01X510237Y479921D02*
G03Y487795I0J3937D01*
G01X537796Y507480D02*
G03X521260I-8268J0D01*
G01D02*
G03X537796I8268J0D01*
G01D02*
G03X521260I-8268J0D01*
G01D02*
G03X537796I8268J0D01*
G01D02*
G03X521260I-8268J0D01*
G01D02*
G03X537796I8268J0D01*
G01D02*
G03X521260I-8268J0D01*
G01D02*
G03X537796I8268J0D01*
G01X521260D02*
G03X537796I8268J0D01*
G01D02*
G03X521260I-8268J0D01*
G01D02*
G03X537796I8268J0D01*
G01D02*
G03X521260I-8268J0D01*
G01X510237Y549606D02*
G03Y557480I0J3937D01*
G01X537796Y577165D02*
G03X521260I-8268J0D01*
G01D02*
G03X537796I8268J0D01*
G01D02*
G03X521260I-8268J0D01*
G01D02*
G03X537796I8268J0D01*
G01D02*
G03X521260I-8268J0D01*
G01D02*
G03X537796I8268J0D01*
G01D02*
G03X521260I-8268J0D01*
G01D02*
G03X537796I8268J0D01*
G01X521260D02*
G03X537796I8268J0D01*
G01D02*
G03X521260I-8268J0D01*
G01D02*
G03X537796I8268J0D01*
G01D02*
G03X521260I-8268J0D01*
G01X510237Y619291D02*
G03Y627165I0J3937D01*
G01X537796Y646850D02*
G03X521260I-8268J0D01*
G01D02*
G03X537796I8268J0D01*
G01D02*
G03X521260I-8268J0D01*
G01D02*
G03X537796I8268J0D01*
G01D02*
G03X521260I-8268J0D01*
G01D02*
G03X537796I8268J0D01*
G01D02*
G03X521260I-8268J0D01*
G01D02*
G03X537796I8268J0D01*
G01X521260D02*
G03X537796I8268J0D01*
G01D02*
G03X521260I-8268J0D01*
G01D02*
G03X537796I8268J0D01*
G01D02*
G03X521260I-8268J0D01*
G01X539370Y-19685D02*
G03X547244Y-11811I0J7874D01*
G01X535433Y0D02*
G03Y-7874I0J-3937D01*
G01X547244D02*
Y-11811D01*
G01X535433Y-7874D02*
X547244D01*
G01Y3937D02*
Y57874D01*
G01X543307Y0D02*
G03X547244Y3937I0J3937D01*
G01X535433Y69685D02*
G03Y61811I0J-3937D01*
G01X547244Y73622D02*
Y127559D01*
G01X543307Y69685D02*
G03X547244Y73622I0J3937D01*
G01Y57874D02*
G03X543307Y61811I-3937J0D01*
G01X535433Y139370D02*
G03Y131496I0J-3937D01*
G01X547244Y143307D02*
Y197244D01*
G01X543307Y139370D02*
G03X547244Y143307I0J3937D01*
G01Y127559D02*
G03X543307Y131496I-3937J0D01*
G01X535433Y278740D02*
G03Y270866I0J-3937D01*
G01Y209055D02*
G03Y201181I0J-3937D01*
G01X543307Y278740D02*
G03X547244Y282677I0J3937D01*
G01Y212992D02*
Y266929D01*
G01X543307Y209055D02*
G03X547244Y212992I0J3937D01*
G01Y266929D02*
G03X543307Y270866I-3937J0D01*
G01X547244Y197244D02*
G03X543307Y201181I-3937J0D01*
G01X535433Y348425D02*
G03Y340551I0J-3937D01*
G01X547244Y352362D02*
Y406299D01*
G01X543307Y348425D02*
G03X547244Y352362I0J3937D01*
G01Y282677D02*
Y336614D01*
G01D02*
G03X543307Y340551I-3937J0D01*
G01X535433Y418110D02*
G03Y410236I0J-3937D01*
G01X547244Y422047D02*
Y475984D01*
G01X543307Y418110D02*
G03X547244Y422047I0J3937D01*
G01Y406299D02*
G03X543307Y410236I-3937J0D01*
G01X535433Y487795D02*
G03Y479921I0J-3937D01*
G01X547244Y491732D02*
Y545669D01*
G01X543307Y487795D02*
G03X547244Y491732I0J3937D01*
G01Y475984D02*
G03X543307Y479921I-3937J0D01*
G01X535433Y557480D02*
G03Y549606I0J-3937D01*
G01X547244Y561417D02*
Y615354D01*
G01X543307Y557480D02*
G03X547244Y561417I0J3937D01*
G01Y545669D02*
G03X543307Y549606I-3937J0D01*
G01X535433Y627165D02*
G03Y619291I0J-3937D01*
G01X547244Y631102D02*
Y685039D01*
G01X543307Y627165D02*
G03X547244Y631102I0J3937D01*
G01Y685039D02*
G03X543307Y688976I-3937J0D01*
G01X547244Y615354D02*
G03X543307Y619291I-3937J0D01*
M02*
